(kicad_pcb
	(version 20260206)
	(generator "pcbnew")
	(generator_version "10.0")
	(general
		(thickness 1.6)
		(legacy_teardrops no)
	)
	(paper "A4")
	(title_block
		(title "01162023_DA0F0TEBIF0_F0T_Expander_BD_F_brd_V02_OCP.brd")
		(comment 1 "Grand Teton / footprints 2825-2831 of 9728")
	)
	(layers
		(0 "F.Cu" signal "TOP")
		(4 "In1.Cu" signal "GND")
		(6 "In2.Cu" signal "VCC")
		(8 "In3.Cu" signal "VCC1")
		(10 "In4.Cu" signal "GND1")
		(12 "In5.Cu" signal "IN1")
		(14 "In6.Cu" signal "GND2")
		(16 "In7.Cu" signal "IN2")
		(18 "In8.Cu" signal "GND3")
		(20 "In9.Cu" signal "IN3")
		(22 "In10.Cu" signal "GND4")
		(24 "In11.Cu" signal "IN4")
		(26 "In12.Cu" signal "GND5")
		(28 "In13.Cu" signal "IN5")
		(30 "In14.Cu" signal "GND6")
		(32 "In15.Cu" signal "IN6")
		(34 "In16.Cu" signal "GND7")
		(2 "B.Cu" signal "BOTTOM")
		(9 "F.Adhes" user "F.Adhesive")
		(11 "B.Adhes" user "B.Adhesive")
		(13 "F.Paste" user "Package Geometry/Pastemask Top")
		(15 "B.Paste" user "Package Geometry/Pastemask Bottom")
		(5 "F.SilkS" user "Ref Des/Silkscreen Top")
		(7 "B.SilkS" user "Ref Des/Silkscreen Bottom")
		(1 "F.Mask" user "Board Geometry/Soldermask Top")
		(3 "B.Mask" user "Board Geometry/Soldermask Bottom")
		(17 "Dwgs.User" user "User.Drawings")
		(19 "Cmts.User" user "User.Comments")
		(21 "Eco1.User" user "User.Eco1")
		(23 "Eco2.User" user "User.Eco2")
		(25 "Edge.Cuts" user "Board Geometry/Outline")
		(27 "Margin" user)
		(31 "F.CrtYd" user "Package Geometry/Place Bound Top")
		(29 "B.CrtYd" user "Package Geometry/Place Bound Bottom")
		(35 "F.Fab" user "Ref Des/Assembly Top")
		(33 "B.Fab" user "Ref Des/Assembly Bottom")
	)
	(footprint ""
		(layer "F.Cu")
		(at 435.02961 -300.62043 90)
		(property "Reference" "R6398"
			(at 0 0 90)
			(layer "F.SilkS")
			(hide yes)
			(effects
				(font
					(size 1.27 1.27)
				)
			)
		)
		(property "Value" ""
			(at 0 0 90)
			(layer "F.Fab")
			(effects
				(font
					(size 1.27 1.27)
				)
			)
		)
		(duplicate_pad_numbers_are_jumpers no)
		(fp_line
			(start 0.7874 -0.4064)
			(end 0.7874 0.4064)
			(stroke
				(width 0.1524)
				(type default)
			)
			(layer "F.SilkS")
		)
		(fp_line
			(start -0.7874 -0.4064)
			(end 0.7874 -0.4064)
			(stroke
				(width 0.1524)
				(type default)
			)
			(layer "F.SilkS")
		)
		(fp_line
			(start 0.7874 0.4064)
			(end -0.7874 0.4064)
			(stroke
				(width 0.1524)
				(type default)
			)
			(layer "F.SilkS")
		)
		(fp_line
			(start -0.7874 0.4064)
			(end -0.7874 -0.4064)
			(stroke
				(width 0.1524)
				(type default)
			)
			(layer "F.SilkS")
		)
		(fp_line
			(start -0.12065 -0.305054)
			(end -0.12065 -0.2794)
			(stroke
				(width 0.1)
				(type default)
			)
			(layer "F.Fab")
		)
		(fp_line
			(start -0.67945 -0.305054)
			(end -0.12065 -0.305054)
			(stroke
				(width 0.1)
				(type default)
			)
			(layer "F.Fab")
		)
		(fp_line
			(start 0.67945 -0.3048)
			(end 0.67945 0.3048)
			(stroke
				(width 0.1)
				(type default)
			)
			(layer "F.Fab")
		)
		(fp_line
			(start 0.12065 -0.3048)
			(end 0.67945 -0.3048)
			(stroke
				(width 0.1)
				(type default)
			)
			(layer "F.Fab")
		)
		(fp_line
			(start 0.12065 -0.2794)
			(end 0.12065 -0.3048)
			(stroke
				(width 0.1)
				(type default)
			)
			(layer "F.Fab")
		)
		(fp_line
			(start -0.12065 -0.2794)
			(end 0.12065 -0.2794)
			(stroke
				(width 0.1)
				(type default)
			)
			(layer "F.Fab")
		)
		(fp_line
			(start 0.120396 0.2794)
			(end -0.12065 0.2794)
			(stroke
				(width 0.1)
				(type default)
			)
			(layer "F.Fab")
		)
		(fp_line
			(start -0.12065 0.2794)
			(end -0.12065 0.3048)
			(stroke
				(width 0.1)
				(type default)
			)
			(layer "F.Fab")
		)
		(fp_line
			(start 0.67945 0.3048)
			(end 0.120396 0.3048)
			(stroke
				(width 0.1)
				(type default)
			)
			(layer "F.Fab")
		)
		(fp_line
			(start 0.120396 0.3048)
			(end 0.120396 0.2794)
			(stroke
				(width 0.1)
				(type default)
			)
			(layer "F.Fab")
		)
		(fp_line
			(start -0.12065 0.3048)
			(end -0.67945 0.3048)
			(stroke
				(width 0.1)
				(type default)
			)
			(layer "F.Fab")
		)
		(fp_line
			(start -0.67945 0.3048)
			(end -0.67945 -0.305054)
			(stroke
				(width 0.1)
				(type default)
			)
			(layer "F.Fab")
		)
		(pad "1" smd circle
			(at -0.40005 0 90)
			(size 0 0)
			(layers "F.Cu" "F.Mask" "F.Paste")
			(net "RST_PEX3_S3_PERST_N")
		)
		(pad "2" smd circle
			(at 0.40005 0 90)
			(size 0 0)
			(layers "F.Cu" "F.Mask" "F.Paste")
			(net "RST_PEX3_S3_PERST_R_N")
		)
	)
	(footprint ""
		(layer "F.Cu")
		(at 442.25464 -124.159264 180)
		(property "Reference" "PC472"
			(at 0 0 180)
			(layer "F.SilkS")
			(hide yes)
			(effects
				(font
					(size 1.27 1.27)
				)
			)
		)
		(property "Value" ""
			(at 0 0 180)
			(layer "F.Fab")
			(effects
				(font
					(size 1.27 1.27)
				)
			)
		)
		(duplicate_pad_numbers_are_jumpers no)
		(fp_line
			(start 0.7874 0.4064)
			(end -0.7874 0.4064)
			(stroke
				(width 0.1524)
				(type default)
			)
			(layer "F.SilkS")
		)
		(fp_line
			(start 0.7874 -0.4064)
			(end 0.7874 0.4064)
			(stroke
				(width 0.1524)
				(type default)
			)
			(layer "F.SilkS")
		)
		(fp_line
			(start -0.7874 0.4064)
			(end -0.7874 -0.4064)
			(stroke
				(width 0.1524)
				(type default)
			)
			(layer "F.SilkS")
		)
		(fp_line
			(start -0.7874 -0.4064)
			(end 0.7874 -0.4064)
			(stroke
				(width 0.1524)
				(type default)
			)
			(layer "F.SilkS")
		)
		(fp_line
			(start 0.67945 0.3048)
			(end 0.120396 0.3048)
			(stroke
				(width 0.1)
				(type default)
			)
			(layer "F.Fab")
		)
		(fp_line
			(start 0.67945 -0.3048)
			(end 0.67945 0.3048)
			(stroke
				(width 0.1)
				(type default)
			)
			(layer "F.Fab")
		)
		(fp_line
			(start 0.12065 -0.2794)
			(end 0.12065 -0.3048)
			(stroke
				(width 0.1)
				(type default)
			)
			(layer "F.Fab")
		)
		(fp_line
			(start 0.12065 -0.3048)
			(end 0.67945 -0.3048)
			(stroke
				(width 0.1)
				(type default)
			)
			(layer "F.Fab")
		)
		(fp_line
			(start 0.120396 0.3048)
			(end 0.120396 0.2794)
			(stroke
				(width 0.1)
				(type default)
			)
			(layer "F.Fab")
		)
		(fp_line
			(start 0.120396 0.2794)
			(end -0.12065 0.2794)
			(stroke
				(width 0.1)
				(type default)
			)
			(layer "F.Fab")
		)
		(fp_line
			(start -0.12065 0.3048)
			(end -0.67945 0.3048)
			(stroke
				(width 0.1)
				(type default)
			)
			(layer "F.Fab")
		)
		(fp_line
			(start -0.12065 0.2794)
			(end -0.12065 0.3048)
			(stroke
				(width 0.1)
				(type default)
			)
			(layer "F.Fab")
		)
		(fp_line
			(start -0.12065 -0.2794)
			(end 0.12065 -0.2794)
			(stroke
				(width 0.1)
				(type default)
			)
			(layer "F.Fab")
		)
		(fp_line
			(start -0.12065 -0.305054)
			(end -0.12065 -0.2794)
			(stroke
				(width 0.1)
				(type default)
			)
			(layer "F.Fab")
		)
		(fp_line
			(start -0.67945 0.3048)
			(end -0.67945 -0.305054)
			(stroke
				(width 0.1)
				(type default)
			)
			(layer "F.Fab")
		)
		(fp_line
			(start -0.67945 -0.305054)
			(end -0.12065 -0.305054)
			(stroke
				(width 0.1)
				(type default)
			)
			(layer "F.Fab")
		)
		(pad "1" smd circle
			(at -0.40005 0 180)
			(size 0 0)
			(layers "F.Cu" "F.Mask" "F.Paste")
			(net "P3V3_AUX")
		)
		(pad "2" smd circle
			(at 0.40005 0 180)
			(size 0 0)
			(layers "F.Cu" "F.Mask" "F.Paste")
			(net "GND")
		)
	)
	(footprint ""
		(layer "F.Cu")
		(at 319.949576 -300.60265 90)
		(property "Reference" "R6396"
			(at 0 0 90)
			(layer "F.SilkS")
			(hide yes)
			(effects
				(font
					(size 1.27 1.27)
				)
			)
		)
		(property "Value" ""
			(at 0 0 90)
			(layer "F.Fab")
			(effects
				(font
					(size 1.27 1.27)
				)
			)
		)
		(duplicate_pad_numbers_are_jumpers no)
		(fp_line
			(start 0.7874 -0.4064)
			(end 0.7874 0.4064)
			(stroke
				(width 0.1524)
				(type default)
			)
			(layer "F.SilkS")
		)
		(fp_line
			(start -0.7874 -0.4064)
			(end 0.7874 -0.4064)
			(stroke
				(width 0.1524)
				(type default)
			)
			(layer "F.SilkS")
		)
		(fp_line
			(start 0.7874 0.4064)
			(end -0.7874 0.4064)
			(stroke
				(width 0.1524)
				(type default)
			)
			(layer "F.SilkS")
		)
		(fp_line
			(start -0.7874 0.4064)
			(end -0.7874 -0.4064)
			(stroke
				(width 0.1524)
				(type default)
			)
			(layer "F.SilkS")
		)
		(fp_line
			(start -0.12065 -0.305054)
			(end -0.12065 -0.2794)
			(stroke
				(width 0.1)
				(type default)
			)
			(layer "F.Fab")
		)
		(fp_line
			(start -0.67945 -0.305054)
			(end -0.12065 -0.305054)
			(stroke
				(width 0.1)
				(type default)
			)
			(layer "F.Fab")
		)
		(fp_line
			(start 0.67945 -0.3048)
			(end 0.67945 0.3048)
			(stroke
				(width 0.1)
				(type default)
			)
			(layer "F.Fab")
		)
		(fp_line
			(start 0.12065 -0.3048)
			(end 0.67945 -0.3048)
			(stroke
				(width 0.1)
				(type default)
			)
			(layer "F.Fab")
		)
		(fp_line
			(start 0.12065 -0.2794)
			(end 0.12065 -0.3048)
			(stroke
				(width 0.1)
				(type default)
			)
			(layer "F.Fab")
		)
		(fp_line
			(start -0.12065 -0.2794)
			(end 0.12065 -0.2794)
			(stroke
				(width 0.1)
				(type default)
			)
			(layer "F.Fab")
		)
		(fp_line
			(start 0.120396 0.2794)
			(end -0.12065 0.2794)
			(stroke
				(width 0.1)
				(type default)
			)
			(layer "F.Fab")
		)
		(fp_line
			(start -0.12065 0.2794)
			(end -0.12065 0.3048)
			(stroke
				(width 0.1)
				(type default)
			)
			(layer "F.Fab")
		)
		(fp_line
			(start 0.67945 0.3048)
			(end 0.120396 0.3048)
			(stroke
				(width 0.1)
				(type default)
			)
			(layer "F.Fab")
		)
		(fp_line
			(start 0.120396 0.3048)
			(end 0.120396 0.2794)
			(stroke
				(width 0.1)
				(type default)
			)
			(layer "F.Fab")
		)
		(fp_line
			(start -0.12065 0.3048)
			(end -0.67945 0.3048)
			(stroke
				(width 0.1)
				(type default)
			)
			(layer "F.Fab")
		)
		(fp_line
			(start -0.67945 0.3048)
			(end -0.67945 -0.305054)
			(stroke
				(width 0.1)
				(type default)
			)
			(layer "F.Fab")
		)
		(pad "1" smd circle
			(at -0.40005 0 90)
			(size 0 0)
			(layers "F.Cu" "F.Mask" "F.Paste")
			(net "RST_PEX2_S1_PERST_N")
		)
		(pad "2" smd circle
			(at 0.40005 0 90)
			(size 0 0)
			(layers "F.Cu" "F.Mask" "F.Paste")
			(net "RST_PEX2_S1_PERST_R_N")
		)
	)
	(footprint ""
		(layer "F.Cu")
		(at 198.76135 -132.601208 180)
		(property "Reference" "C232"
			(at 0 0 180)
			(layer "F.SilkS")
			(hide yes)
			(effects
				(font
					(size 1.27 1.27)
				)
			)
		)
		(property "Value" ""
			(at 0 0 180)
			(layer "F.Fab")
			(effects
				(font
					(size 1.27 1.27)
				)
			)
		)
		(duplicate_pad_numbers_are_jumpers no)
		(fp_line
			(start 0.299974 0.150114)
			(end -0.299974 0.150114)
			(stroke
				(width 0.1)
				(type default)
			)
			(layer "F.Fab")
		)
		(fp_line
			(start 0.299974 -0.150114)
			(end 0.299974 0.150114)
			(stroke
				(width 0.1)
				(type default)
			)
			(layer "F.Fab")
		)
		(fp_line
			(start -0.299974 0.150114)
			(end -0.299974 -0.150114)
			(stroke
				(width 0.1)
				(type default)
			)
			(layer "F.Fab")
		)
		(fp_line
			(start -0.299974 -0.150114)
			(end 0.299974 -0.150114)
			(stroke
				(width 0.1)
				(type default)
			)
			(layer "F.Fab")
		)
		(pad "1" smd rect
			(at -0.2667 0 180)
			(size 0.3048 0.381)
			(layers "F.Cu" "F.Mask" "F.Paste")
			(net "P5E_PEX1_STN0_TX_DP<5>")
		)
		(pad "2" smd rect
			(at 0.2667 0 180)
			(size 0.3048 0.381)
			(layers "F.Cu" "F.Mask" "F.Paste")
			(net "P5E_PEX1_STN0_TX_C_DP<5>")
		)
	)
	(footprint ""
		(layer "F.Cu")
		(at 242.493292 -221.050612 180)
		(property "Reference" "R4853"
			(at 0 0 180)
			(layer "F.SilkS")
			(hide yes)
			(effects
				(font
					(size 1.27 1.27)
				)
			)
		)
		(property "Value" ""
			(at 0 0 180)
			(layer "F.Fab")
			(effects
				(font
					(size 1.27 1.27)
				)
			)
		)
		(duplicate_pad_numbers_are_jumpers no)
		(fp_line
			(start 0.7874 0.4064)
			(end -0.7874 0.4064)
			(stroke
				(width 0.1524)
				(type default)
			)
			(layer "F.SilkS")
		)
		(fp_line
			(start 0.7874 -0.4064)
			(end 0.7874 0.4064)
			(stroke
				(width 0.1524)
				(type default)
			)
			(layer "F.SilkS")
		)
		(fp_line
			(start -0.7874 0.4064)
			(end -0.7874 -0.4064)
			(stroke
				(width 0.1524)
				(type default)
			)
			(layer "F.SilkS")
		)
		(fp_line
			(start -0.7874 -0.4064)
			(end 0.7874 -0.4064)
			(stroke
				(width 0.1524)
				(type default)
			)
			(layer "F.SilkS")
		)
		(fp_line
			(start 0.67945 0.3048)
			(end 0.120396 0.3048)
			(stroke
				(width 0.1)
				(type default)
			)
			(layer "F.Fab")
		)
		(fp_line
			(start 0.67945 -0.3048)
			(end 0.67945 0.3048)
			(stroke
				(width 0.1)
				(type default)
			)
			(layer "F.Fab")
		)
		(fp_line
			(start 0.12065 -0.2794)
			(end 0.12065 -0.3048)
			(stroke
				(width 0.1)
				(type default)
			)
			(layer "F.Fab")
		)
		(fp_line
			(start 0.12065 -0.3048)
			(end 0.67945 -0.3048)
			(stroke
				(width 0.1)
				(type default)
			)
			(layer "F.Fab")
		)
		(fp_line
			(start 0.120396 0.3048)
			(end 0.120396 0.2794)
			(stroke
				(width 0.1)
				(type default)
			)
			(layer "F.Fab")
		)
		(fp_line
			(start 0.120396 0.2794)
			(end -0.12065 0.2794)
			(stroke
				(width 0.1)
				(type default)
			)
			(layer "F.Fab")
		)
		(fp_line
			(start -0.12065 0.3048)
			(end -0.67945 0.3048)
			(stroke
				(width 0.1)
				(type default)
			)
			(layer "F.Fab")
		)
		(fp_line
			(start -0.12065 0.2794)
			(end -0.12065 0.3048)
			(stroke
				(width 0.1)
				(type default)
			)
			(layer "F.Fab")
		)
		(fp_line
			(start -0.12065 -0.2794)
			(end 0.12065 -0.2794)
			(stroke
				(width 0.1)
				(type default)
			)
			(layer "F.Fab")
		)
		(fp_line
			(start -0.12065 -0.305054)
			(end -0.12065 -0.2794)
			(stroke
				(width 0.1)
				(type default)
			)
			(layer "F.Fab")
		)
		(fp_line
			(start -0.67945 0.3048)
			(end -0.67945 -0.305054)
			(stroke
				(width 0.1)
				(type default)
			)
			(layer "F.Fab")
		)
		(fp_line
			(start -0.67945 -0.305054)
			(end -0.12065 -0.305054)
			(stroke
				(width 0.1)
				(type default)
			)
			(layer "F.Fab")
		)
		(pad "1" smd circle
			(at -0.40005 0 180)
			(size 0 0)
			(layers "F.Cu" "F.Mask" "F.Paste")
			(net "PD_BIC_ADCREXT1")
		)
		(pad "2" smd circle
			(at 0.40005 0 180)
			(size 0 0)
			(layers "F.Cu" "F.Mask" "F.Paste")
			(net "GND")
		)
	)
	(footprint ""
		(layer "F.Cu")
		(at 217.583512 -231.416606 -90)
		(property "Reference" "R4553"
			(at 0 0 270)
			(layer "F.SilkS")
			(hide yes)
			(effects
				(font
					(size 1.27 1.27)
				)
			)
		)
		(property "Value" ""
			(at 0 0 270)
			(layer "F.Fab")
			(effects
				(font
					(size 1.27 1.27)
				)
			)
		)
		(duplicate_pad_numbers_are_jumpers no)
		(fp_line
			(start -0.7874 0.4064)
			(end -0.7874 -0.4064)
			(stroke
				(width 0.1524)
				(type default)
			)
			(layer "F.SilkS")
		)
		(fp_line
			(start 0.7874 0.4064)
			(end -0.7874 0.4064)
			(stroke
				(width 0.1524)
				(type default)
			)
			(layer "F.SilkS")
		)
		(fp_line
			(start -0.7874 -0.4064)
			(end 0.7874 -0.4064)
			(stroke
				(width 0.1524)
				(type default)
			)
			(layer "F.SilkS")
		)
		(fp_line
			(start 0.7874 -0.4064)
			(end 0.7874 0.4064)
			(stroke
				(width 0.1524)
				(type default)
			)
			(layer "F.SilkS")
		)
		(fp_line
			(start -0.67945 0.3048)
			(end -0.67945 -0.305054)
			(stroke
				(width 0.1)
				(type default)
			)
			(layer "F.Fab")
		)
		(fp_line
			(start -0.12065 0.3048)
			(end -0.67945 0.3048)
			(stroke
				(width 0.1)
				(type default)
			)
			(layer "F.Fab")
		)
		(fp_line
			(start 0.120396 0.3048)
			(end 0.120396 0.2794)
			(stroke
				(width 0.1)
				(type default)
			)
			(layer "F.Fab")
		)
		(fp_line
			(start 0.67945 0.3048)
			(end 0.120396 0.3048)
			(stroke
				(width 0.1)
				(type default)
			)
			(layer "F.Fab")
		)
		(fp_line
			(start -0.12065 0.2794)
			(end -0.12065 0.3048)
			(stroke
				(width 0.1)
				(type default)
			)
			(layer "F.Fab")
		)
		(fp_line
			(start 0.120396 0.2794)
			(end -0.12065 0.2794)
			(stroke
				(width 0.1)
				(type default)
			)
			(layer "F.Fab")
		)
		(fp_line
			(start -0.12065 -0.2794)
			(end 0.12065 -0.2794)
			(stroke
				(width 0.1)
				(type default)
			)
			(layer "F.Fab")
		)
		(fp_line
			(start 0.12065 -0.2794)
			(end 0.12065 -0.3048)
			(stroke
				(width 0.1)
				(type default)
			)
			(layer "F.Fab")
		)
		(fp_line
			(start 0.12065 -0.3048)
			(end 0.67945 -0.3048)
			(stroke
				(width 0.1)
				(type default)
			)
			(layer "F.Fab")
		)
		(fp_line
			(start 0.67945 -0.3048)
			(end 0.67945 0.3048)
			(stroke
				(width 0.1)
				(type default)
			)
			(layer "F.Fab")
		)
		(fp_line
			(start -0.67945 -0.305054)
			(end -0.12065 -0.305054)
			(stroke
				(width 0.1)
				(type default)
			)
			(layer "F.Fab")
		)
		(fp_line
			(start -0.12065 -0.305054)
			(end -0.12065 -0.2794)
			(stroke
				(width 0.1)
				(type default)
			)
			(layer "F.Fab")
		)
		(pad "1" smd circle
			(at -0.40005 0 270)
			(size 0 0)
			(layers "F.Cu" "F.Mask" "F.Paste")
			(net "GND")
		)
		(pad "2" smd circle
			(at 0.40005 0 270)
			(size 0 0)
			(layers "F.Cu" "F.Mask" "F.Paste")
			(net "BOARD_ID0")
		)
	)
	(footprint ""
		(layer "F.Cu")
		(at 399.362422 -22.955504 -90)
		(property "Reference" "C2741"
			(at 0 0 270)
			(layer "F.SilkS")
			(hide yes)
			(effects
				(font
					(size 1.27 1.27)
				)
			)
		)
		(property "Value" ""
			(at 0 0 270)
			(layer "F.Fab")
			(effects
				(font
					(size 1.27 1.27)
				)
			)
		)
		(duplicate_pad_numbers_are_jumpers no)
		(fp_line
			(start -0.7874 0.4064)
			(end -0.7874 -0.4064)
			(stroke
				(width 0.1524)
				(type default)
			)
			(layer "F.SilkS")
		)
		(fp_line
			(start 0.7874 0.4064)
			(end -0.7874 0.4064)
			(stroke
				(width 0.1524)
				(type default)
			)
			(layer "F.SilkS")
		)
		(fp_line
			(start -0.7874 -0.4064)
			(end 0.7874 -0.4064)
			(stroke
				(width 0.1524)
				(type default)
			)
			(layer "F.SilkS")
		)
		(fp_line
			(start 0.7874 -0.4064)
			(end 0.7874 0.4064)
			(stroke
				(width 0.1524)
				(type default)
			)
			(layer "F.SilkS")
		)
		(fp_line
			(start -0.67945 0.3048)
			(end -0.67945 -0.305054)
			(stroke
				(width 0.1)
				(type default)
			)
			(layer "F.Fab")
		)
		(fp_line
			(start -0.12065 0.3048)
			(end -0.67945 0.3048)
			(stroke
				(width 0.1)
				(type default)
			)
			(layer "F.Fab")
		)
		(fp_line
			(start 0.120396 0.3048)
			(end 0.120396 0.2794)
			(stroke
				(width 0.1)
				(type default)
			)
			(layer "F.Fab")
		)
		(fp_line
			(start 0.67945 0.3048)
			(end 0.120396 0.3048)
			(stroke
				(width 0.1)
				(type default)
			)
			(layer "F.Fab")
		)
		(fp_line
			(start -0.12065 0.2794)
			(end -0.12065 0.3048)
			(stroke
				(width 0.1)
				(type default)
			)
			(layer "F.Fab")
		)
		(fp_line
			(start 0.120396 0.2794)
			(end -0.12065 0.2794)
			(stroke
				(width 0.1)
				(type default)
			)
			(layer "F.Fab")
		)
		(fp_line
			(start -0.12065 -0.2794)
			(end 0.12065 -0.2794)
			(stroke
				(width 0.1)
				(type default)
			)
			(layer "F.Fab")
		)
		(fp_line
			(start 0.12065 -0.2794)
			(end 0.12065 -0.3048)
			(stroke
				(width 0.1)
				(type default)
			)
			(layer "F.Fab")
		)
		(fp_line
			(start 0.12065 -0.3048)
			(end 0.67945 -0.3048)
			(stroke
				(width 0.1)
				(type default)
			)
			(layer "F.Fab")
		)
		(fp_line
			(start 0.67945 -0.3048)
			(end 0.67945 0.3048)
			(stroke
				(width 0.1)
				(type default)
			)
			(layer "F.Fab")
		)
		(fp_line
			(start -0.67945 -0.305054)
			(end -0.12065 -0.305054)
			(stroke
				(width 0.1)
				(type default)
			)
			(layer "F.Fab")
		)
		(fp_line
			(start -0.12065 -0.305054)
			(end -0.12065 -0.2794)
			(stroke
				(width 0.1)
				(type default)
			)
			(layer "F.Fab")
		)
		(pad "1" smd circle
			(at -0.40005 0 270)
			(size 0 0)
			(layers "F.Cu" "F.Mask" "F.Paste")
			(net "GND")
		)
		(pad "2" smd circle
			(at 0.40005 0 270)
			(size 0 0)
			(layers "F.Cu" "F.Mask" "F.Paste")
			(net "P3V3_AUX")
		)
	)
)
